FILE_TYPE = MULTI_PHYS_TABLE;

PART 'OSC6P_V2'
CLASS = DISCRETE

{========================================================================================}
:CLS_PN             = JEDEC_TYPE            |ALT_SYMBOLS               |DESCRIPTION                                                         | CPN_STATUS ;
{========================================================================================}
 'G130-10052-01'    = 'SMC_Y6_197X126_V1'   |'(SMC_Y6_197X126_V1)'     |'OSC,125M,50PPM,-40C~85C,3.3V, MEMS DIFF TYPE, 5MMX3.2MM,SMD6'      |'NFND'
 'G130-10053-01'    = 'SMC_Y6_197X126_V1'   |'(SMC_Y6_197X126_V1)'     |'OSC,25M,50PPM,-40C~85C,3.3V, MEMS DIFF TYPE, 5MMX3.2MM,SMD6'       |''
 'G130-10070-01'    = 'SMC_Y6_197X126_V1'   |'(SMC_Y6_197X126_V1)'     |'OSC,3.3V,LVPECL,50PPM,-20~70C,6PAD 5X3.2MM SMD'                    |'NFND'
 'G130-10082-01'    = 'SMC_OSC6_276X197_V2' |'(SMC_OSC6_276X197_V2)'   |'OSC,CXO,50.00MHZ,3.3V LVPECL,50PPM,7MMX5MM SMT'                    |'NFND'
 'G130-10009-01'    = 'SMC_Y6_197X126'      |'(SMC_Y6_197X126)'        |'OSC,100MHZ,PECL,3.3V,50PPM,5.0X3.2MM,SMT'                          |'NFND'
 'G130-10093-01'    = 'SMC_OSC6_276X197_V2' |'(SMC_OSC6_276X197_V2)'   |'OSC,CXO,100MHZ,3.3V LVPECL,25PPM,-40~85C,7.0X5.0MM,SMD'            |'NFND'
 'G130-10100-01'    = 'SMC_Y6_276X197_V8'   |'(SMC_Y6_276X197_V8)'     |'OSC,MEMS XO,100MHZ,3.3V,LVPECL,50PPM,0.7PS,-20~70C,7X5MM,SMT'      |'NFND'
 'G130-10101-01'    = 'SMC_Y6_276X197_V8'   |'(SMC_Y6_276X197_V8)'     |'OSC,MEMS XO,25MHZ,3.3V,LVPECL,25PPM,0.7PS,-20~70C,7X5MM,SMT'       |'NFND'
 'G130-10088-01'    = 'SMC_OSC6_276X197_V2' |'(SMC_OSC6_276X197_V2)'   |'OSC,50MHZ,3.3V LVDS,50PPM,7X5MM,SMT'                               |'NFND'
 'G130-10124-01'    = 'SMC_Y6_126X098'      |'(SMC_Y6_126X098)'        |'OSC,CXO,156.253906MHZ,25PPM,-40-85C,3.3V, LVPECL,3.2MMX2.5MM, SMD' |''
 'G130-10127-01'    = 'SMC_Y6_197X126_V2'   | '(SMC_Y6_197X126_V2)'    | 'OSC, XO, 100MHZ,3.3V,LVPECL,50PPM,5X3.2MM,SMT, -20~70C'           |''
 'G130-10056-01'    = 'SMC_Y6_276X197_V4'   | '(SMC_Y6_276X197_V4)'    | 'OSC,212.500000MHZ,DIFF,3.3V,LVDS,100PPM,7X5MM,SMT'                |'OBSOLETE'
 'A130-00001-AW'    = 'SMC_Y6_126X098_V2'   | '(SMC_Y6_126X098_V2)'    | 'OSC,XO,100MHZ,3.3V LVPECL,50PPM,3.2MMX2.5MM,SMT'                  |''
 'G130-10152-01'    = 'SMC_Y6_197X126_V2'   | '(SMC_Y6_197X126_V2)'    | 'OSC,XO,50MHZ,3.3V,50PPM,5X3.2MM,SMT'                              |''
 'A130-00002-AW'    = 'SMC_Y6_197X126_V2'   | '(SMC_Y6_197X126_V2)'    | 'OSC, XO, 100MHZ,3.3V,LVPECL,LVDS,HCSL,50PPM,5X3.2MM,SMT, -40~85C,' |''
 'A130-00003-AW'    = 'SMC_Y6_126X197'      | '(SMC_Y6_126X197)'       | 'OSC,5032 XO,200MHZ,+-50PPM,3.3V,150FS,LVDS QFM6,SMT'               |''
 'A130-00004-AW'    = 'SMC_Y6_197X276'      | '(SMC_Y6_197X276)'       | 'OSC,7050 XO,125MHZ,+-50PPM,3.3V,90FS,LVDS QFM6,SMT'                |''

 
END_PART

END.

